(kicad_pcb
	(version 20260206)
	(generator "pcbnew")
	(generator_version "10.0")
	(general
		(thickness 1.6)
		(legacy_teardrops no)
	)
	(paper "A4")
	(title_block
		(title "01162023_DA0F0TEBIF0_F0T_Expander_BD_F_brd_V02_OCP.brd")
		(comment 1 "Grand Teton / footprints 6216-6219 of 9728")
	)
	(layers
		(0 "F.Cu" signal "TOP")
		(4 "In1.Cu" signal "GND")
		(6 "In2.Cu" signal "VCC")
		(8 "In3.Cu" signal "VCC1")
		(10 "In4.Cu" signal "GND1")
		(12 "In5.Cu" signal "IN1")
		(14 "In6.Cu" signal "GND2")
		(16 "In7.Cu" signal "IN2")
		(18 "In8.Cu" signal "GND3")
		(20 "In9.Cu" signal "IN3")
		(22 "In10.Cu" signal "GND4")
		(24 "In11.Cu" signal "IN4")
		(26 "In12.Cu" signal "GND5")
		(28 "In13.Cu" signal "IN5")
		(30 "In14.Cu" signal "GND6")
		(32 "In15.Cu" signal "IN6")
		(34 "In16.Cu" signal "GND7")
		(2 "B.Cu" signal "BOTTOM")
		(9 "F.Adhes" user "F.Adhesive")
		(11 "B.Adhes" user "B.Adhesive")
		(13 "F.Paste" user "Package Geometry/Pastemask Top")
		(15 "B.Paste" user "Package Geometry/Pastemask Bottom")
		(5 "F.SilkS" user "Ref Des/Silkscreen Top")
		(7 "B.SilkS" user "Ref Des/Silkscreen Bottom")
		(1 "F.Mask" user "Board Geometry/Soldermask Top")
		(3 "B.Mask" user "Board Geometry/Soldermask Bottom")
		(17 "Dwgs.User" user "User.Drawings")
		(19 "Cmts.User" user "User.Comments")
		(21 "Eco1.User" user "User.Eco1")
		(23 "Eco2.User" user "User.Eco2")
		(25 "Edge.Cuts" user "Board Geometry/Outline")
		(27 "Margin" user)
		(31 "F.CrtYd" user "Package Geometry/Place Bound Top")
		(29 "B.CrtYd" user "Package Geometry/Place Bound Bottom")
		(35 "F.Fab" user "Ref Des/Assembly Top")
		(33 "B.Fab" user "Ref Des/Assembly Bottom")
	)
	(footprint ""
		(layer "F.Cu")
		(at 326.303386 -96.811592 90)
		(property "Reference" "R742"
			(at 0 0 90)
			(layer "F.SilkS")
			(hide yes)
			(effects
				(font
					(size 1.27 1.27)
				)
			)
		)
		(property "Value" ""
			(at 0 0 90)
			(layer "F.Fab")
			(effects
				(font
					(size 1.27 1.27)
				)
			)
		)
		(duplicate_pad_numbers_are_jumpers no)
		(fp_line
			(start 0.7874 -0.4064)
			(end 0.7874 0.4064)
			(stroke
				(width 0.1524)
				(type default)
			)
			(layer "F.SilkS")
		)
		(fp_line
			(start -0.7874 -0.4064)
			(end 0.7874 -0.4064)
			(stroke
				(width 0.1524)
				(type default)
			)
			(layer "F.SilkS")
		)
		(fp_line
			(start 0.7874 0.4064)
			(end -0.7874 0.4064)
			(stroke
				(width 0.1524)
				(type default)
			)
			(layer "F.SilkS")
		)
		(fp_line
			(start -0.7874 0.4064)
			(end -0.7874 -0.4064)
			(stroke
				(width 0.1524)
				(type default)
			)
			(layer "F.SilkS")
		)
		(fp_line
			(start -0.12065 -0.305054)
			(end -0.12065 -0.2794)
			(stroke
				(width 0.1)
				(type default)
			)
			(layer "F.Fab")
		)
		(fp_line
			(start -0.67945 -0.305054)
			(end -0.12065 -0.305054)
			(stroke
				(width 0.1)
				(type default)
			)
			(layer "F.Fab")
		)
		(fp_line
			(start 0.67945 -0.3048)
			(end 0.67945 0.3048)
			(stroke
				(width 0.1)
				(type default)
			)
			(layer "F.Fab")
		)
		(fp_line
			(start 0.12065 -0.3048)
			(end 0.67945 -0.3048)
			(stroke
				(width 0.1)
				(type default)
			)
			(layer "F.Fab")
		)
		(fp_line
			(start 0.12065 -0.2794)
			(end 0.12065 -0.3048)
			(stroke
				(width 0.1)
				(type default)
			)
			(layer "F.Fab")
		)
		(fp_line
			(start -0.12065 -0.2794)
			(end 0.12065 -0.2794)
			(stroke
				(width 0.1)
				(type default)
			)
			(layer "F.Fab")
		)
		(fp_line
			(start 0.120396 0.2794)
			(end -0.12065 0.2794)
			(stroke
				(width 0.1)
				(type default)
			)
			(layer "F.Fab")
		)
		(fp_line
			(start -0.12065 0.2794)
			(end -0.12065 0.3048)
			(stroke
				(width 0.1)
				(type default)
			)
			(layer "F.Fab")
		)
		(fp_line
			(start 0.67945 0.3048)
			(end 0.120396 0.3048)
			(stroke
				(width 0.1)
				(type default)
			)
			(layer "F.Fab")
		)
		(fp_line
			(start 0.120396 0.3048)
			(end 0.120396 0.2794)
			(stroke
				(width 0.1)
				(type default)
			)
			(layer "F.Fab")
		)
		(fp_line
			(start -0.12065 0.3048)
			(end -0.67945 0.3048)
			(stroke
				(width 0.1)
				(type default)
			)
			(layer "F.Fab")
		)
		(fp_line
			(start -0.67945 0.3048)
			(end -0.67945 -0.305054)
			(stroke
				(width 0.1)
				(type default)
			)
			(layer "F.Fab")
		)
		(pad "1" smd circle
			(at -0.40005 0 90)
			(size 0 0)
			(layers "F.Cu" "F.Mask" "F.Paste")
			(net "SMB_BIC_I2C6_MUX_NIC_ADC_R_SCL")
		)
		(pad "2" smd circle
			(at 0.40005 0 90)
			(size 0 0)
			(layers "F.Cu" "F.Mask" "F.Paste")
			(net "SMB_NIC5_ADC_SCL")
		)
	)
	(footprint ""
		(layer "F.Cu")
		(at 73.53046 -66.32194 -90)
		(property "Reference" "PC656"
			(at 0 0 270)
			(layer "F.SilkS")
			(hide yes)
			(effects
				(font
					(size 1.27 1.27)
				)
			)
		)
		(property "Value" ""
			(at 0 0 270)
			(layer "F.Fab")
			(effects
				(font
					(size 1.27 1.27)
				)
			)
		)
		(duplicate_pad_numbers_are_jumpers no)
		(fp_line
			(start -0.7874 0.4064)
			(end -0.7874 -0.4064)
			(stroke
				(width 0.1524)
				(type default)
			)
			(layer "F.SilkS")
		)
		(fp_line
			(start 0.7874 0.4064)
			(end -0.7874 0.4064)
			(stroke
				(width 0.1524)
				(type default)
			)
			(layer "F.SilkS")
		)
		(fp_line
			(start -0.7874 -0.4064)
			(end 0.7874 -0.4064)
			(stroke
				(width 0.1524)
				(type default)
			)
			(layer "F.SilkS")
		)
		(fp_line
			(start 0.7874 -0.4064)
			(end 0.7874 0.4064)
			(stroke
				(width 0.1524)
				(type default)
			)
			(layer "F.SilkS")
		)
		(fp_line
			(start -0.67945 0.3048)
			(end -0.67945 -0.305054)
			(stroke
				(width 0.1)
				(type default)
			)
			(layer "F.Fab")
		)
		(fp_line
			(start -0.12065 0.3048)
			(end -0.67945 0.3048)
			(stroke
				(width 0.1)
				(type default)
			)
			(layer "F.Fab")
		)
		(fp_line
			(start 0.120396 0.3048)
			(end 0.120396 0.2794)
			(stroke
				(width 0.1)
				(type default)
			)
			(layer "F.Fab")
		)
		(fp_line
			(start 0.67945 0.3048)
			(end 0.120396 0.3048)
			(stroke
				(width 0.1)
				(type default)
			)
			(layer "F.Fab")
		)
		(fp_line
			(start -0.12065 0.2794)
			(end -0.12065 0.3048)
			(stroke
				(width 0.1)
				(type default)
			)
			(layer "F.Fab")
		)
		(fp_line
			(start 0.120396 0.2794)
			(end -0.12065 0.2794)
			(stroke
				(width 0.1)
				(type default)
			)
			(layer "F.Fab")
		)
		(fp_line
			(start -0.12065 -0.2794)
			(end 0.12065 -0.2794)
			(stroke
				(width 0.1)
				(type default)
			)
			(layer "F.Fab")
		)
		(fp_line
			(start 0.12065 -0.2794)
			(end 0.12065 -0.3048)
			(stroke
				(width 0.1)
				(type default)
			)
			(layer "F.Fab")
		)
		(fp_line
			(start 0.12065 -0.3048)
			(end 0.67945 -0.3048)
			(stroke
				(width 0.1)
				(type default)
			)
			(layer "F.Fab")
		)
		(fp_line
			(start 0.67945 -0.3048)
			(end 0.67945 0.3048)
			(stroke
				(width 0.1)
				(type default)
			)
			(layer "F.Fab")
		)
		(fp_line
			(start -0.67945 -0.305054)
			(end -0.12065 -0.305054)
			(stroke
				(width 0.1)
				(type default)
			)
			(layer "F.Fab")
		)
		(fp_line
			(start -0.12065 -0.305054)
			(end -0.12065 -0.2794)
			(stroke
				(width 0.1)
				(type default)
			)
			(layer "F.Fab")
		)
		(pad "1" smd circle
			(at -0.40005 0 270)
			(size 0 0)
			(layers "F.Cu" "F.Mask" "F.Paste")
			(net "P12V_SSD2_CO_DV_DT")
		)
		(pad "2" smd circle
			(at 0.40005 0 270)
			(size 0 0)
			(layers "F.Cu" "F.Mask" "F.Paste")
			(net "GND")
		)
	)
	(footprint ""
		(layer "F.Cu")
		(at 280.847038 -54.3941)
		(property "Reference" "PU40"
			(at -2.000758 2.902204 0)
			(unlocked yes)
			(layer "F.SilkS")
			(effects
				(font
					(size 0.7874 0.5842)
					(thickness 0.1524)
				)
				(justify left)
			)
		)
		(property "Value" ""
			(at 0 0 0)
			(layer "F.Fab")
			(effects
				(font
					(size 1.27 1.27)
				)
			)
		)
		(duplicate_pad_numbers_are_jumpers no)
		(fp_line
			(start -1.943608 -1.549908)
			(end 1.943608 -1.549908)
			(stroke
				(width 0.1524)
				(type default)
			)
			(layer "F.SilkS")
		)
		(fp_line
			(start -1.943608 1.549908)
			(end -1.943608 -1.549908)
			(stroke
				(width 0.1524)
				(type default)
			)
			(layer "F.SilkS")
		)
		(fp_line
			(start 1.943608 -1.549908)
			(end 1.943608 1.549908)
			(stroke
				(width 0.1524)
				(type default)
			)
			(layer "F.SilkS")
		)
		(fp_line
			(start 1.943608 1.549908)
			(end -1.943608 1.549908)
			(stroke
				(width 0.1524)
				(type default)
			)
			(layer "F.SilkS")
		)
		(fp_poly
			(pts
				(xy -2.019808 -1.549908) (xy -1.257808 -1.549908) (xy -1.257808 -1.880108) (xy -2.019808 -1.880108)
			)
			(stroke
				(width 0)
				(type default)
			)
			(fill yes)
			(layer "F.SilkS")
		)
		(fp_line
			(start -1.549908 -1.549908)
			(end 1.549908 -1.549908)
			(stroke
				(width 0.1)
				(type default)
			)
			(layer "F.Fab")
		)
		(fp_line
			(start -1.549908 1.549908)
			(end -1.549908 -1.549908)
			(stroke
				(width 0.1)
				(type default)
			)
			(layer "F.Fab")
		)
		(fp_line
			(start 1.549908 -1.549908)
			(end 1.549908 1.549908)
			(stroke
				(width 0.1)
				(type default)
			)
			(layer "F.Fab")
		)
		(fp_line
			(start 1.549908 1.549908)
			(end -1.549908 1.549908)
			(stroke
				(width 0.1)
				(type default)
			)
			(layer "F.Fab")
		)
		(fp_poly
			(pts
				(xy -2.019808 -1.549908) (xy -1.257808 -1.549908) (xy -1.257808 -1.880108) (xy -2.019808 -1.880108)
			)
			(stroke
				(width 0)
				(type default)
			)
			(fill yes)
			(layer "F.Fab")
		)
		(pad "1" smd rect
			(at -1.500124 -1.249934 270)
			(size 0.2794 0.6096)
			(layers "F.Cu" "F.Mask" "F.Paste")
			(net "P12V_SSD9_R")
		)
		(pad "2" smd rect
			(at -1.500124 -0.750062 270)
			(size 0.2794 0.6096)
			(layers "F.Cu" "F.Mask" "F.Paste")
			(net "P12V_SSD9_R")
		)
		(pad "3" smd rect
			(at -1.500124 -0.249936 270)
			(size 0.2794 0.6096)
			(layers "F.Cu" "F.Mask" "F.Paste")
			(net "P12V_SSD9_R")
		)
		(pad "4" smd rect
			(at -1.500124 0.249936 270)
			(size 0.2794 0.6096)
			(layers "F.Cu" "F.Mask" "F.Paste")
			(net "P12V_SSD9_R")
		)
		(pad "5" smd rect
			(at -1.500124 0.750062 270)
			(size 0.2794 0.6096)
			(layers "F.Cu" "F.Mask" "F.Paste")
			(net "P12V_SSD9_R")
		)
		(pad "6" smd rect
			(at -1.500124 1.249934 270)
			(size 0.2794 0.6096)
			(layers "F.Cu" "F.Mask" "F.Paste")
			(net "GND")
		)
		(pad "7" smd rect
			(at 1.500124 1.249934 270)
			(size 0.2794 0.6096)
			(layers "F.Cu" "F.Mask" "F.Paste")
			(net "P12V_SSD9_SS")
		)
		(pad "8" smd rect
			(at 1.500124 0.750062 270)
			(size 0.2794 0.6096)
			(layers "F.Cu" "F.Mask" "F.Paste")
			(net "PWRGD_P12V_SSD9")
		)
		(pad "9" smd rect
			(at 1.500124 0.249936 270)
			(size 0.2794 0.6096)
			(layers "F.Cu" "F.Mask" "F.Paste")
			(net "P12V_SSD9_OCP")
		)
		(pad "10" smd rect
			(at 1.500124 -0.249936 270)
			(size 0.2794 0.6096)
			(layers "F.Cu" "F.Mask" "F.Paste")
			(net "P5V_AUX")
		)
		(pad "11" smd rect
			(at 1.500124 -0.750062 270)
			(size 0.2794 0.6096)
			(layers "F.Cu" "F.Mask" "F.Paste")
			(net "SSD9_PWR_EN_R")
		)
		(pad "12" smd rect
			(at 1.500124 -1.249934 270)
			(size 0.2794 0.6096)
			(layers "F.Cu" "F.Mask" "F.Paste")
			(net "P12V_AUX")
		)
		(pad "13" smd rect
			(at 0 0)
			(size 1.9812 2.7178)
			(layers "F.Cu" "F.Mask" "F.Paste")
			(net "P12V_AUX")
		)
		(zone
			(layer "F.Cu")
			(hatch none 0.5)
			(connect_pads
				(clearance 0)
			)
			(min_thickness 0.25)
			(keepout
				(tracks not_allowed)
				(vias allowed)
				(pads allowed)
				(copperpour not_allowed)
				(footprints allowed)
			)
			(placement
				(enabled no)
				(sheetname "")
			)
			(fill
				(thermal_gap 0.5)
				(thermal_bridge_width 0.5)
				(island_removal_mode 0)
			)
			(polygon
				(pts
					(xy 281.990038 -55.9435) (xy 281.990038 -55.8165) (xy 281.990038 -52.8447) (xy 281.990038 -52.844192)
					(xy 279.704038 -52.844192) (xy 279.704038 -52.8447) (xy 279.704038 -52.9717) (xy 279.704038 -54.3941)
					(xy 279.805638 -54.3941) (xy 279.805638 -52.9717) (xy 281.888438 -52.9717) (xy 281.888438 -55.8165)
					(xy 279.805638 -55.8165) (xy 279.805638 -54.4195) (xy 279.704038 -54.4195) (xy 279.704038 -55.8165)
					(xy 279.704038 -55.9435) (xy 279.704038 -55.944008) (xy 281.990038 -55.944008)
				)
			)
		)
	)
	(footprint ""
		(layer "F.Cu")
		(at 307.867812 -19.453098)
		(property "Reference" "R1709"
			(at 0 0 0)
			(layer "F.SilkS")
			(hide yes)
			(effects
				(font
					(size 1.27 1.27)
				)
			)
		)
		(property "Value" ""
			(at 0 0 0)
			(layer "F.Fab")
			(effects
				(font
					(size 1.27 1.27)
				)
			)
		)
		(duplicate_pad_numbers_are_jumpers no)
		(fp_line
			(start -0.7874 -0.4064)
			(end 0.7874 -0.4064)
			(stroke
				(width 0.1524)
				(type default)
			)
			(layer "F.SilkS")
		)
		(fp_line
			(start -0.7874 0.4064)
			(end -0.7874 -0.4064)
			(stroke
				(width 0.1524)
				(type default)
			)
			(layer "F.SilkS")
		)
		(fp_line
			(start 0.7874 -0.4064)
			(end 0.7874 0.4064)
			(stroke
				(width 0.1524)
				(type default)
			)
			(layer "F.SilkS")
		)
		(fp_line
			(start 0.7874 0.4064)
			(end -0.7874 0.4064)
			(stroke
				(width 0.1524)
				(type default)
			)
			(layer "F.SilkS")
		)
		(fp_line
			(start -0.67945 -0.305054)
			(end -0.12065 -0.305054)
			(stroke
				(width 0.1)
				(type default)
			)
			(layer "F.Fab")
		)
		(fp_line
			(start -0.67945 0.3048)
			(end -0.67945 -0.305054)
			(stroke
				(width 0.1)
				(type default)
			)
			(layer "F.Fab")
		)
		(fp_line
			(start -0.12065 -0.305054)
			(end -0.12065 -0.2794)
			(stroke
				(width 0.1)
				(type default)
			)
			(layer "F.Fab")
		)
		(fp_line
			(start -0.12065 -0.2794)
			(end 0.12065 -0.2794)
			(stroke
				(width 0.1)
				(type default)
			)
			(layer "F.Fab")
		)
		(fp_line
			(start -0.12065 0.2794)
			(end -0.12065 0.3048)
			(stroke
				(width 0.1)
				(type default)
			)
			(layer "F.Fab")
		)
		(fp_line
			(start -0.12065 0.3048)
			(end -0.67945 0.3048)
			(stroke
				(width 0.1)
				(type default)
			)
			(layer "F.Fab")
		)
		(fp_line
			(start 0.120396 0.2794)
			(end -0.12065 0.2794)
			(stroke
				(width 0.1)
				(type default)
			)
			(layer "F.Fab")
		)
		(fp_line
			(start 0.120396 0.3048)
			(end 0.120396 0.2794)
			(stroke
				(width 0.1)
				(type default)
			)
			(layer "F.Fab")
		)
		(fp_line
			(start 0.12065 -0.3048)
			(end 0.67945 -0.3048)
			(stroke
				(width 0.1)
				(type default)
			)
			(layer "F.Fab")
		)
		(fp_line
			(start 0.12065 -0.2794)
			(end 0.12065 -0.3048)
			(stroke
				(width 0.1)
				(type default)
			)
			(layer "F.Fab")
		)
		(fp_line
			(start 0.67945 -0.3048)
			(end 0.67945 0.3048)
			(stroke
				(width 0.1)
				(type default)
			)
			(layer "F.Fab")
		)
		(fp_line
			(start 0.67945 0.3048)
			(end 0.120396 0.3048)
			(stroke
				(width 0.1)
				(type default)
			)
			(layer "F.Fab")
		)
		(pad "1" smd circle
			(at -0.40005 0)
			(size 0 0)
			(layers "F.Cu" "F.Mask" "F.Paste")
			(net "SMB_ISO_SSD10_R_SDA")
		)
		(pad "2" smd circle
			(at 0.40005 0)
			(size 0 0)
			(layers "F.Cu" "F.Mask" "F.Paste")
			(net "SMB_ISO_SSD10_SDA")
		)
	)
)
